(kicad_pcb
	(version 20260206)
	(generator "pcbnew")
	(generator_version "10.0")
	(general
		(thickness 1.6)
		(legacy_teardrops no)
	)
	(paper "A4")
	(title_block
		(title "01162023_DA0F0TEBIF0_F0T_Expander_BD_F_brd_V02_OCP.brd")
		(comment 1 "Grand Teton / footprints 6600-6601 of 9728")
	)
	(layers
		(0 "F.Cu" signal "TOP")
		(4 "In1.Cu" signal "GND")
		(6 "In2.Cu" signal "VCC")
		(8 "In3.Cu" signal "VCC1")
		(10 "In4.Cu" signal "GND1")
		(12 "In5.Cu" signal "IN1")
		(14 "In6.Cu" signal "GND2")
		(16 "In7.Cu" signal "IN2")
		(18 "In8.Cu" signal "GND3")
		(20 "In9.Cu" signal "IN3")
		(22 "In10.Cu" signal "GND4")
		(24 "In11.Cu" signal "IN4")
		(26 "In12.Cu" signal "GND5")
		(28 "In13.Cu" signal "IN5")
		(30 "In14.Cu" signal "GND6")
		(32 "In15.Cu" signal "IN6")
		(34 "In16.Cu" signal "GND7")
		(2 "B.Cu" signal "BOTTOM")
		(9 "F.Adhes" user "F.Adhesive")
		(11 "B.Adhes" user "B.Adhesive")
		(13 "F.Paste" user "Package Geometry/Pastemask Top")
		(15 "B.Paste" user "Package Geometry/Pastemask Bottom")
		(5 "F.SilkS" user "Ref Des/Silkscreen Top")
		(7 "B.SilkS" user "Ref Des/Silkscreen Bottom")
		(1 "F.Mask" user "Board Geometry/Soldermask Top")
		(3 "B.Mask" user "Board Geometry/Soldermask Bottom")
		(17 "Dwgs.User" user "User.Drawings")
		(19 "Cmts.User" user "User.Comments")
		(21 "Eco1.User" user "User.Eco1")
		(23 "Eco2.User" user "User.Eco2")
		(25 "Edge.Cuts" user "Board Geometry/Outline")
		(27 "Margin" user)
		(31 "F.CrtYd" user "Package Geometry/Place Bound Top")
		(29 "B.CrtYd" user "Package Geometry/Place Bound Bottom")
		(35 "F.Fab" user "Ref Des/Assembly Top")
		(33 "B.Fab" user "Ref Des/Assembly Bottom")
	)
	(footprint ""
		(layer "F.Cu")
		(at 351.455228 -53.468524 90)
		(property "Reference" "PC581"
			(at 0 0 90)
			(layer "F.SilkS")
			(hide yes)
			(effects
				(font
					(size 1.27 1.27)
				)
			)
		)
		(property "Value" ""
			(at 0 0 90)
			(layer "F.Fab")
			(effects
				(font
					(size 1.27 1.27)
				)
			)
		)
		(duplicate_pad_numbers_are_jumpers no)
		(fp_line
			(start 1.524 -0.762)
			(end 1.524 0.762)
			(stroke
				(width 0.1524)
				(type default)
			)
			(layer "F.SilkS")
		)
		(fp_line
			(start -1.524 -0.762)
			(end 1.524 -0.762)
			(stroke
				(width 0.1524)
				(type default)
			)
			(layer "F.SilkS")
		)
		(fp_line
			(start 1.524 0.762)
			(end -1.524 0.762)
			(stroke
				(width 0.1524)
				(type default)
			)
			(layer "F.SilkS")
		)
		(fp_line
			(start -1.524 0.762)
			(end -1.524 -0.762)
			(stroke
				(width 0.1524)
				(type default)
			)
			(layer "F.SilkS")
		)
		(fp_line
			(start 1.1049 -0.724916)
			(end -1.1049 -0.724916)
			(stroke
				(width 0.1)
				(type default)
			)
			(layer "F.Fab")
		)
		(fp_line
			(start -1.1049 -0.724916)
			(end -1.1049 0.724916)
			(stroke
				(width 0.1)
				(type default)
			)
			(layer "F.Fab")
		)
		(fp_line
			(start 1.1049 0.724916)
			(end 1.1049 -0.724916)
			(stroke
				(width 0.1)
				(type default)
			)
			(layer "F.Fab")
		)
		(fp_line
			(start -1.1049 0.724916)
			(end 1.1049 0.724916)
			(stroke
				(width 0.1)
				(type default)
			)
			(layer "F.Fab")
		)
		(pad "1" smd rect
			(at -0.889 0 270)
			(size 1.016 1.27)
			(layers "F.Cu" "F.Mask" "F.Paste")
			(net "GND")
		)
		(pad "2" smd rect
			(at 0.889 0 270)
			(size 1.016 1.27)
			(layers "F.Cu" "F.Mask" "F.Paste")
			(net "P3V3_AUX")
		)
	)
	(footprint ""
		(layer "F.Cu")
		(at 328.92238 -44.341542 90)
		(property "Reference" "R635"
			(at 0 0 90)
			(layer "F.SilkS")
			(hide yes)
			(effects
				(font
					(size 1.27 1.27)
				)
			)
		)
		(property "Value" ""
			(at 0 0 90)
			(layer "F.Fab")
			(effects
				(font
					(size 1.27 1.27)
				)
			)
		)
		(duplicate_pad_numbers_are_jumpers no)
		(fp_line
			(start 0.7874 -0.4064)
			(end 0.7874 0.4064)
			(stroke
				(width 0.1524)
				(type default)
			)
			(layer "F.SilkS")
		)
		(fp_line
			(start -0.7874 -0.4064)
			(end 0.7874 -0.4064)
			(stroke
				(width 0.1524)
				(type default)
			)
			(layer "F.SilkS")
		)
		(fp_line
			(start 0.7874 0.4064)
			(end -0.7874 0.4064)
			(stroke
				(width 0.1524)
				(type default)
			)
			(layer "F.SilkS")
		)
		(fp_line
			(start -0.7874 0.4064)
			(end -0.7874 -0.4064)
			(stroke
				(width 0.1524)
				(type default)
			)
			(layer "F.SilkS")
		)
		(fp_line
			(start -0.12065 -0.305054)
			(end -0.12065 -0.2794)
			(stroke
				(width 0.1)
				(type default)
			)
			(layer "F.Fab")
		)
		(fp_line
			(start -0.67945 -0.305054)
			(end -0.12065 -0.305054)
			(stroke
				(width 0.1)
				(type default)
			)
			(layer "F.Fab")
		)
		(fp_line
			(start 0.67945 -0.3048)
			(end 0.67945 0.3048)
			(stroke
				(width 0.1)
				(type default)
			)
			(layer "F.Fab")
		)
		(fp_line
			(start 0.12065 -0.3048)
			(end 0.67945 -0.3048)
			(stroke
				(width 0.1)
				(type default)
			)
			(layer "F.Fab")
		)
		(fp_line
			(start 0.12065 -0.2794)
			(end 0.12065 -0.3048)
			(stroke
				(width 0.1)
				(type default)
			)
			(layer "F.Fab")
		)
		(fp_line
			(start -0.12065 -0.2794)
			(end 0.12065 -0.2794)
			(stroke
				(width 0.1)
				(type default)
			)
			(layer "F.Fab")
		)
		(fp_line
			(start 0.120396 0.2794)
			(end -0.12065 0.2794)
			(stroke
				(width 0.1)
				(type default)
			)
			(layer "F.Fab")
		)
		(fp_line
			(start -0.12065 0.2794)
			(end -0.12065 0.3048)
			(stroke
				(width 0.1)
				(type default)
			)
			(layer "F.Fab")
		)
		(fp_line
			(start 0.67945 0.3048)
			(end 0.120396 0.3048)
			(stroke
				(width 0.1)
				(type default)
			)
			(layer "F.Fab")
		)
		(fp_line
			(start 0.120396 0.3048)
			(end 0.120396 0.2794)
			(stroke
				(width 0.1)
				(type default)
			)
			(layer "F.Fab")
		)
		(fp_line
			(start -0.12065 0.3048)
			(end -0.67945 0.3048)
			(stroke
				(width 0.1)
				(type default)
			)
			(layer "F.Fab")
		)
		(fp_line
			(start -0.67945 0.3048)
			(end -0.67945 -0.305054)
			(stroke
				(width 0.1)
				(type default)
			)
			(layer "F.Fab")
		)
		(pad "1" smd circle
			(at -0.40005 0 90)
			(size 0 0)
			(layers "F.Cu" "F.Mask" "F.Paste")
			(net "P12V_SSD11")
		)
		(pad "2" smd circle
			(at 0.40005 0 90)
			(size 0 0)
			(layers "F.Cu" "F.Mask" "F.Paste")
			(net "P12V_SSD11_VIN_N")
		)
	)
)
